(kicad_pcb
	(version 20260206)
	(generator "pcbnew")
	(generator_version "10.0")
	(general
		(thickness 1.6)
		(legacy_teardrops no)
	)
	(paper "A4")
	(title_block
		(title "03242023_DA0F0TMBIJ0_F0T_Motherboard_J_brd_V01_OCP.brd")
		(comment 1 "Grand Teton / footprints 2170-2176 of 6105")
	)
	(layers
		(0 "F.Cu" signal "TOP")
		(4 "In1.Cu" signal "GND")
		(6 "In2.Cu" signal "IN1")
		(8 "In3.Cu" signal "GND1")
		(10 "In4.Cu" signal "IN2")
		(12 "In5.Cu" signal "GND2")
		(14 "In6.Cu" signal "IN3")
		(16 "In7.Cu" signal "GND3")
		(18 "In8.Cu" signal "VCC")
		(20 "In9.Cu" signal "VCC1")
		(22 "In10.Cu" signal "GND4")
		(24 "In11.Cu" signal "IN4")
		(26 "In12.Cu" signal "GND5")
		(28 "In13.Cu" signal "IN5")
		(30 "In14.Cu" signal "GND6")
		(32 "In15.Cu" signal "IN6")
		(34 "In16.Cu" signal "GND7")
		(2 "B.Cu" signal "BOTTOM")
		(9 "F.Adhes" user "F.Adhesive")
		(11 "B.Adhes" user "B.Adhesive")
		(13 "F.Paste" user "Package Geometry/Pastemask Top")
		(15 "B.Paste" user "Package Geometry/Pastemask Bottom")
		(5 "F.SilkS" user "Ref Des/Silkscreen Top")
		(7 "B.SilkS" user "Ref Des/Silkscreen Bottom")
		(1 "F.Mask" user "Board Geometry/Soldermask Top")
		(3 "B.Mask" user "Board Geometry/Soldermask Bottom")
		(17 "Dwgs.User" user "User.Drawings")
		(19 "Cmts.User" user "User.Comments")
		(21 "Eco1.User" user "User.Eco1")
		(23 "Eco2.User" user "User.Eco2")
		(25 "Edge.Cuts" user "Board Geometry/Outline")
		(27 "Margin" user)
		(31 "F.CrtYd" user "Package Geometry/Place Bound Top")
		(29 "B.CrtYd" user "Package Geometry/Place Bound Bottom")
		(35 "F.Fab" user "Ref Des/Assembly Top")
		(33 "B.Fab" user "Ref Des/Assembly Bottom")
	)
	(footprint ""
		(layer "F.Cu")
		(at 336.319622 -63.363348 -90)
		(property "Reference" "R1720"
			(at 0 0 270)
			(layer "F.SilkS")
			(hide yes)
			(effects
				(font
					(size 1.27 1.27)
				)
			)
		)
		(property "Value" ""
			(at 0 0 270)
			(layer "F.Fab")
			(effects
				(font
					(size 1.27 1.27)
				)
			)
		)
		(duplicate_pad_numbers_are_jumpers no)
		(fp_line
			(start -0.7874 0.4064)
			(end -0.7874 -0.4064)
			(stroke
				(width 0.1524)
				(type default)
			)
			(layer "F.SilkS")
		)
		(fp_line
			(start 0.7874 0.4064)
			(end -0.7874 0.4064)
			(stroke
				(width 0.1524)
				(type default)
			)
			(layer "F.SilkS")
		)
		(fp_line
			(start -0.7874 -0.4064)
			(end 0.7874 -0.4064)
			(stroke
				(width 0.1524)
				(type default)
			)
			(layer "F.SilkS")
		)
		(fp_line
			(start 0.7874 -0.4064)
			(end 0.7874 0.4064)
			(stroke
				(width 0.1524)
				(type default)
			)
			(layer "F.SilkS")
		)
		(fp_line
			(start -0.67945 0.3048)
			(end -0.67945 -0.305054)
			(stroke
				(width 0.1)
				(type default)
			)
			(layer "F.Fab")
		)
		(fp_line
			(start -0.12065 0.3048)
			(end -0.67945 0.3048)
			(stroke
				(width 0.1)
				(type default)
			)
			(layer "F.Fab")
		)
		(fp_line
			(start 0.120396 0.3048)
			(end 0.120396 0.2794)
			(stroke
				(width 0.1)
				(type default)
			)
			(layer "F.Fab")
		)
		(fp_line
			(start 0.67945 0.3048)
			(end 0.120396 0.3048)
			(stroke
				(width 0.1)
				(type default)
			)
			(layer "F.Fab")
		)
		(fp_line
			(start -0.12065 0.2794)
			(end -0.12065 0.3048)
			(stroke
				(width 0.1)
				(type default)
			)
			(layer "F.Fab")
		)
		(fp_line
			(start 0.120396 0.2794)
			(end -0.12065 0.2794)
			(stroke
				(width 0.1)
				(type default)
			)
			(layer "F.Fab")
		)
		(fp_line
			(start -0.12065 -0.2794)
			(end 0.12065 -0.2794)
			(stroke
				(width 0.1)
				(type default)
			)
			(layer "F.Fab")
		)
		(fp_line
			(start 0.12065 -0.2794)
			(end 0.12065 -0.3048)
			(stroke
				(width 0.1)
				(type default)
			)
			(layer "F.Fab")
		)
		(fp_line
			(start 0.12065 -0.3048)
			(end 0.67945 -0.3048)
			(stroke
				(width 0.1)
				(type default)
			)
			(layer "F.Fab")
		)
		(fp_line
			(start 0.67945 -0.3048)
			(end 0.67945 0.3048)
			(stroke
				(width 0.1)
				(type default)
			)
			(layer "F.Fab")
		)
		(fp_line
			(start -0.67945 -0.305054)
			(end -0.12065 -0.305054)
			(stroke
				(width 0.1)
				(type default)
			)
			(layer "F.Fab")
		)
		(fp_line
			(start -0.12065 -0.305054)
			(end -0.12065 -0.2794)
			(stroke
				(width 0.1)
				(type default)
			)
			(layer "F.Fab")
		)
		(pad "1" smd circle
			(at -0.40005 0 270)
			(size 0 0)
			(layers "F.Cu" "F.Mask" "F.Paste")
			(net "XTAL_PCH_25M_IN_R")
		)
		(pad "2" smd circle
			(at 0.40005 0 270)
			(size 0 0)
			(layers "F.Cu" "F.Mask" "F.Paste")
			(net "XTAL_PCH_25M_IN")
		)
	)
	(footprint ""
		(layer "F.Cu")
		(at 125.26772 -164.447728)
		(property "Reference" ""
			(at 0 0 0)
			(layer "F.SilkS")
			(hide yes)
			(effects
				(font
					(size 1.27 1.27)
				)
			)
		)
		(property "Value" ""
			(at 0 0 0)
			(layer "F.Fab")
			(effects
				(font
					(size 1.27 1.27)
				)
			)
		)
		(duplicate_pad_numbers_are_jumpers no)
		(pad "1" smd circle
			(at 0 0)
			(size 0.9906 0.9906)
			(layers "F.Cu" "F.Mask" "F.Paste")
			(net "Net_290")
		)
		(zone
			(layer "F.Cu")
			(hatch none 0.5)
			(connect_pads
				(clearance 0)
			)
			(min_thickness 0.25)
			(keepout
				(tracks not_allowed)
				(vias allowed)
				(pads allowed)
				(copperpour not_allowed)
				(footprints allowed)
			)
			(placement
				(enabled no)
				(sheetname "")
			)
			(fill
				(thermal_gap 0.5)
				(thermal_bridge_width 0.5)
				(island_removal_mode 0)
			)
			(polygon
				(pts
					(arc
						(start 126.89332 -164.447728)
						(mid 123.64212 -164.447728)
						(end 126.89332 -164.447728)
					)
				)
			)
		)
	)
	(footprint ""
		(layer "F.Cu")
		(at 27.628596 -396.390876)
		(property "Reference" "R3281"
			(at 0 0 0)
			(layer "F.SilkS")
			(hide yes)
			(effects
				(font
					(size 1.27 1.27)
				)
			)
		)
		(property "Value" ""
			(at 0 0 0)
			(layer "F.Fab")
			(effects
				(font
					(size 1.27 1.27)
				)
			)
		)
		(duplicate_pad_numbers_are_jumpers no)
		(fp_line
			(start -0.7874 -0.4064)
			(end 0.7874 -0.4064)
			(stroke
				(width 0.1524)
				(type default)
			)
			(layer "F.SilkS")
		)
		(fp_line
			(start -0.7874 0.4064)
			(end -0.7874 -0.4064)
			(stroke
				(width 0.1524)
				(type default)
			)
			(layer "F.SilkS")
		)
		(fp_line
			(start 0.7874 -0.4064)
			(end 0.7874 0.4064)
			(stroke
				(width 0.1524)
				(type default)
			)
			(layer "F.SilkS")
		)
		(fp_line
			(start 0.7874 0.4064)
			(end -0.7874 0.4064)
			(stroke
				(width 0.1524)
				(type default)
			)
			(layer "F.SilkS")
		)
		(fp_line
			(start -0.67945 -0.305054)
			(end -0.12065 -0.305054)
			(stroke
				(width 0.1)
				(type default)
			)
			(layer "F.Fab")
		)
		(fp_line
			(start -0.67945 0.3048)
			(end -0.67945 -0.305054)
			(stroke
				(width 0.1)
				(type default)
			)
			(layer "F.Fab")
		)
		(fp_line
			(start -0.12065 -0.305054)
			(end -0.12065 -0.2794)
			(stroke
				(width 0.1)
				(type default)
			)
			(layer "F.Fab")
		)
		(fp_line
			(start -0.12065 -0.2794)
			(end 0.12065 -0.2794)
			(stroke
				(width 0.1)
				(type default)
			)
			(layer "F.Fab")
		)
		(fp_line
			(start -0.12065 0.2794)
			(end -0.12065 0.3048)
			(stroke
				(width 0.1)
				(type default)
			)
			(layer "F.Fab")
		)
		(fp_line
			(start -0.12065 0.3048)
			(end -0.67945 0.3048)
			(stroke
				(width 0.1)
				(type default)
			)
			(layer "F.Fab")
		)
		(fp_line
			(start 0.120396 0.2794)
			(end -0.12065 0.2794)
			(stroke
				(width 0.1)
				(type default)
			)
			(layer "F.Fab")
		)
		(fp_line
			(start 0.120396 0.3048)
			(end 0.120396 0.2794)
			(stroke
				(width 0.1)
				(type default)
			)
			(layer "F.Fab")
		)
		(fp_line
			(start 0.12065 -0.3048)
			(end 0.67945 -0.3048)
			(stroke
				(width 0.1)
				(type default)
			)
			(layer "F.Fab")
		)
		(fp_line
			(start 0.12065 -0.2794)
			(end 0.12065 -0.3048)
			(stroke
				(width 0.1)
				(type default)
			)
			(layer "F.Fab")
		)
		(fp_line
			(start 0.67945 -0.3048)
			(end 0.67945 0.3048)
			(stroke
				(width 0.1)
				(type default)
			)
			(layer "F.Fab")
		)
		(fp_line
			(start 0.67945 0.3048)
			(end 0.120396 0.3048)
			(stroke
				(width 0.1)
				(type default)
			)
			(layer "F.Fab")
		)
		(pad "1" smd circle
			(at -0.40005 0)
			(size 0 0)
			(layers "F.Cu" "F.Mask" "F.Paste")
			(net "FM_P2E_EQB1")
		)
		(pad "2" smd circle
			(at 0.40005 0)
			(size 0 0)
			(layers "F.Cu" "F.Mask" "F.Paste")
			(net "GND")
		)
	)
	(footprint ""
		(layer "F.Cu")
		(at 395.550898 -160.13049 90)
		(property "Reference" "C567"
			(at 0 0 90)
			(layer "F.SilkS")
			(hide yes)
			(effects
				(font
					(size 1.27 1.27)
				)
			)
		)
		(property "Value" ""
			(at 0 0 90)
			(layer "F.Fab")
			(effects
				(font
					(size 1.27 1.27)
				)
			)
		)
		(duplicate_pad_numbers_are_jumpers no)
		(fp_line
			(start 0.7874 -0.4064)
			(end 0.7874 0.4064)
			(stroke
				(width 0.1524)
				(type default)
			)
			(layer "F.SilkS")
		)
		(fp_line
			(start -0.7874 -0.4064)
			(end 0.7874 -0.4064)
			(stroke
				(width 0.1524)
				(type default)
			)
			(layer "F.SilkS")
		)
		(fp_line
			(start 0.7874 0.4064)
			(end -0.7874 0.4064)
			(stroke
				(width 0.1524)
				(type default)
			)
			(layer "F.SilkS")
		)
		(fp_line
			(start -0.7874 0.4064)
			(end -0.7874 -0.4064)
			(stroke
				(width 0.1524)
				(type default)
			)
			(layer "F.SilkS")
		)
		(fp_line
			(start -0.12065 -0.305054)
			(end -0.12065 -0.2794)
			(stroke
				(width 0.1)
				(type default)
			)
			(layer "F.Fab")
		)
		(fp_line
			(start -0.67945 -0.305054)
			(end -0.12065 -0.305054)
			(stroke
				(width 0.1)
				(type default)
			)
			(layer "F.Fab")
		)
		(fp_line
			(start 0.67945 -0.3048)
			(end 0.67945 0.3048)
			(stroke
				(width 0.1)
				(type default)
			)
			(layer "F.Fab")
		)
		(fp_line
			(start 0.12065 -0.3048)
			(end 0.67945 -0.3048)
			(stroke
				(width 0.1)
				(type default)
			)
			(layer "F.Fab")
		)
		(fp_line
			(start 0.12065 -0.2794)
			(end 0.12065 -0.3048)
			(stroke
				(width 0.1)
				(type default)
			)
			(layer "F.Fab")
		)
		(fp_line
			(start -0.12065 -0.2794)
			(end 0.12065 -0.2794)
			(stroke
				(width 0.1)
				(type default)
			)
			(layer "F.Fab")
		)
		(fp_line
			(start 0.120396 0.2794)
			(end -0.12065 0.2794)
			(stroke
				(width 0.1)
				(type default)
			)
			(layer "F.Fab")
		)
		(fp_line
			(start -0.12065 0.2794)
			(end -0.12065 0.3048)
			(stroke
				(width 0.1)
				(type default)
			)
			(layer "F.Fab")
		)
		(fp_line
			(start 0.67945 0.3048)
			(end 0.120396 0.3048)
			(stroke
				(width 0.1)
				(type default)
			)
			(layer "F.Fab")
		)
		(fp_line
			(start 0.120396 0.3048)
			(end 0.120396 0.2794)
			(stroke
				(width 0.1)
				(type default)
			)
			(layer "F.Fab")
		)
		(fp_line
			(start -0.12065 0.3048)
			(end -0.67945 0.3048)
			(stroke
				(width 0.1)
				(type default)
			)
			(layer "F.Fab")
		)
		(fp_line
			(start -0.67945 0.3048)
			(end -0.67945 -0.305054)
			(stroke
				(width 0.1)
				(type default)
			)
			(layer "F.Fab")
		)
		(pad "1" smd circle
			(at -0.40005 0 90)
			(size 0 0)
			(layers "F.Cu" "F.Mask" "F.Paste")
			(net "PVNN_TERM_CPU0")
		)
		(pad "2" smd circle
			(at 0.40005 0 90)
			(size 0 0)
			(layers "F.Cu" "F.Mask" "F.Paste")
			(net "GND")
		)
	)
	(footprint ""
		(layer "F.Cu")
		(at 303.457102 -28.997656 90)
		(property "Reference" "U62"
			(at 1.246378 -4.518914 0)
			(unlocked yes)
			(layer "F.SilkS")
			(effects
				(font
					(size 0.7874 0.5842)
					(thickness 0.1524)
				)
				(justify left)
			)
		)
		(property "Value" ""
			(at 0 0 90)
			(layer "F.Fab")
			(effects
				(font
					(size 1.27 1.27)
				)
			)
		)
		(duplicate_pad_numbers_are_jumpers no)
		(fp_line
			(start 1.584198 -1.500124)
			(end -1.584198 -1.500124)
			(stroke
				(width 0.1524)
				(type default)
			)
			(layer "F.SilkS")
		)
		(fp_line
			(start -1.584198 -1.500124)
			(end -1.584198 1.500124)
			(stroke
				(width 0.1524)
				(type default)
			)
			(layer "F.SilkS")
		)
		(fp_line
			(start 1.584198 1.500124)
			(end 1.584198 -1.500124)
			(stroke
				(width 0.1524)
				(type default)
			)
			(layer "F.SilkS")
		)
		(fp_line
			(start -1.584198 1.500124)
			(end 1.584198 1.500124)
			(stroke
				(width 0.1524)
				(type default)
			)
			(layer "F.SilkS")
		)
		(fp_line
			(start 0.700024 -1.500124)
			(end -0.700024 -1.500124)
			(stroke
				(width 0.1)
				(type default)
			)
			(layer "F.Fab")
		)
		(fp_line
			(start -0.700024 -1.500124)
			(end -0.700024 1.500124)
			(stroke
				(width 0.1)
				(type default)
			)
			(layer "F.Fab")
		)
		(fp_line
			(start 0.700024 1.500124)
			(end 0.700024 -1.500124)
			(stroke
				(width 0.1)
				(type default)
			)
			(layer "F.Fab")
		)
		(fp_line
			(start -0.700024 1.500124)
			(end 0.700024 1.500124)
			(stroke
				(width 0.1)
				(type default)
			)
			(layer "F.Fab")
		)
		(pad "1" smd rect
			(at -0.999998 -0.94996)
			(size 0.8128 0.9144)
			(layers "F.Cu" "F.Mask" "F.Paste")
			(net "P3V_BAT_R")
		)
		(pad "2" smd rect
			(at -0.999998 0.94996)
			(size 0.8128 0.9144)
			(layers "F.Cu" "F.Mask" "F.Paste")
			(net "P3V3_AUX")
		)
		(pad "3" smd rect
			(at 0.999998 0)
			(size 0.8128 0.9144)
			(layers "F.Cu" "F.Mask" "F.Paste")
			(net "P3V3_RTC_AUX")
		)
	)
	(footprint ""
		(layer "F.Cu")
		(at 355.216714 -255.053846 90)
		(property "Reference" "C994"
			(at 0 0 90)
			(layer "F.SilkS")
			(hide yes)
			(effects
				(font
					(size 1.27 1.27)
				)
			)
		)
		(property "Value" ""
			(at 0 0 90)
			(layer "F.Fab")
			(effects
				(font
					(size 1.27 1.27)
				)
			)
		)
		(duplicate_pad_numbers_are_jumpers no)
		(fp_line
			(start 0.7874 -0.4064)
			(end 0.7874 0.4064)
			(stroke
				(width 0.1524)
				(type default)
			)
			(layer "F.SilkS")
		)
		(fp_line
			(start -0.7874 -0.4064)
			(end 0.7874 -0.4064)
			(stroke
				(width 0.1524)
				(type default)
			)
			(layer "F.SilkS")
		)
		(fp_line
			(start 0.7874 0.4064)
			(end -0.7874 0.4064)
			(stroke
				(width 0.1524)
				(type default)
			)
			(layer "F.SilkS")
		)
		(fp_line
			(start -0.7874 0.4064)
			(end -0.7874 -0.4064)
			(stroke
				(width 0.1524)
				(type default)
			)
			(layer "F.SilkS")
		)
		(fp_line
			(start -0.12065 -0.305054)
			(end -0.12065 -0.2794)
			(stroke
				(width 0.1)
				(type default)
			)
			(layer "F.Fab")
		)
		(fp_line
			(start -0.67945 -0.305054)
			(end -0.12065 -0.305054)
			(stroke
				(width 0.1)
				(type default)
			)
			(layer "F.Fab")
		)
		(fp_line
			(start 0.67945 -0.3048)
			(end 0.67945 0.3048)
			(stroke
				(width 0.1)
				(type default)
			)
			(layer "F.Fab")
		)
		(fp_line
			(start 0.12065 -0.3048)
			(end 0.67945 -0.3048)
			(stroke
				(width 0.1)
				(type default)
			)
			(layer "F.Fab")
		)
		(fp_line
			(start 0.12065 -0.2794)
			(end 0.12065 -0.3048)
			(stroke
				(width 0.1)
				(type default)
			)
			(layer "F.Fab")
		)
		(fp_line
			(start -0.12065 -0.2794)
			(end 0.12065 -0.2794)
			(stroke
				(width 0.1)
				(type default)
			)
			(layer "F.Fab")
		)
		(fp_line
			(start 0.120396 0.2794)
			(end -0.12065 0.2794)
			(stroke
				(width 0.1)
				(type default)
			)
			(layer "F.Fab")
		)
		(fp_line
			(start -0.12065 0.2794)
			(end -0.12065 0.3048)
			(stroke
				(width 0.1)
				(type default)
			)
			(layer "F.Fab")
		)
		(fp_line
			(start 0.67945 0.3048)
			(end 0.120396 0.3048)
			(stroke
				(width 0.1)
				(type default)
			)
			(layer "F.Fab")
		)
		(fp_line
			(start 0.120396 0.3048)
			(end 0.120396 0.2794)
			(stroke
				(width 0.1)
				(type default)
			)
			(layer "F.Fab")
		)
		(fp_line
			(start -0.12065 0.3048)
			(end -0.67945 0.3048)
			(stroke
				(width 0.1)
				(type default)
			)
			(layer "F.Fab")
		)
		(fp_line
			(start -0.67945 0.3048)
			(end -0.67945 -0.305054)
			(stroke
				(width 0.1)
				(type default)
			)
			(layer "F.Fab")
		)
		(pad "1" smd circle
			(at -0.40005 0 90)
			(size 0 0)
			(layers "F.Cu" "F.Mask" "F.Paste")
			(net "PVCCIN_CPU0")
		)
		(pad "2" smd circle
			(at 0.40005 0 90)
			(size 0 0)
			(layers "F.Cu" "F.Mask" "F.Paste")
			(net "GND")
		)
	)
	(footprint ""
		(layer "F.Cu")
		(at 106.331004 -244.032024 90)
		(property "Reference" "C300"
			(at 0 0 90)
			(layer "F.SilkS")
			(hide yes)
			(effects
				(font
					(size 1.27 1.27)
				)
			)
		)
		(property "Value" ""
			(at 0 0 90)
			(layer "F.Fab")
			(effects
				(font
					(size 1.27 1.27)
				)
			)
		)
		(duplicate_pad_numbers_are_jumpers no)
		(fp_line
			(start 0.7874 -0.4064)
			(end 0.7874 0.4064)
			(stroke
				(width 0.1524)
				(type default)
			)
			(layer "F.SilkS")
		)
		(fp_line
			(start -0.7874 -0.4064)
			(end 0.7874 -0.4064)
			(stroke
				(width 0.1524)
				(type default)
			)
			(layer "F.SilkS")
		)
		(fp_line
			(start 0.7874 0.4064)
			(end -0.7874 0.4064)
			(stroke
				(width 0.1524)
				(type default)
			)
			(layer "F.SilkS")
		)
		(fp_line
			(start -0.7874 0.4064)
			(end -0.7874 -0.4064)
			(stroke
				(width 0.1524)
				(type default)
			)
			(layer "F.SilkS")
		)
		(fp_line
			(start -0.12065 -0.305054)
			(end -0.12065 -0.2794)
			(stroke
				(width 0.1)
				(type default)
			)
			(layer "F.Fab")
		)
		(fp_line
			(start -0.67945 -0.305054)
			(end -0.12065 -0.305054)
			(stroke
				(width 0.1)
				(type default)
			)
			(layer "F.Fab")
		)
		(fp_line
			(start 0.67945 -0.3048)
			(end 0.67945 0.3048)
			(stroke
				(width 0.1)
				(type default)
			)
			(layer "F.Fab")
		)
		(fp_line
			(start 0.12065 -0.3048)
			(end 0.67945 -0.3048)
			(stroke
				(width 0.1)
				(type default)
			)
			(layer "F.Fab")
		)
		(fp_line
			(start 0.12065 -0.2794)
			(end 0.12065 -0.3048)
			(stroke
				(width 0.1)
				(type default)
			)
			(layer "F.Fab")
		)
		(fp_line
			(start -0.12065 -0.2794)
			(end 0.12065 -0.2794)
			(stroke
				(width 0.1)
				(type default)
			)
			(layer "F.Fab")
		)
		(fp_line
			(start 0.120396 0.2794)
			(end -0.12065 0.2794)
			(stroke
				(width 0.1)
				(type default)
			)
			(layer "F.Fab")
		)
		(fp_line
			(start -0.12065 0.2794)
			(end -0.12065 0.3048)
			(stroke
				(width 0.1)
				(type default)
			)
			(layer "F.Fab")
		)
		(fp_line
			(start 0.67945 0.3048)
			(end 0.120396 0.3048)
			(stroke
				(width 0.1)
				(type default)
			)
			(layer "F.Fab")
		)
		(fp_line
			(start 0.120396 0.3048)
			(end 0.120396 0.2794)
			(stroke
				(width 0.1)
				(type default)
			)
			(layer "F.Fab")
		)
		(fp_line
			(start -0.12065 0.3048)
			(end -0.67945 0.3048)
			(stroke
				(width 0.1)
				(type default)
			)
			(layer "F.Fab")
		)
		(fp_line
			(start -0.67945 0.3048)
			(end -0.67945 -0.305054)
			(stroke
				(width 0.1)
				(type default)
			)
			(layer "F.Fab")
		)
		(pad "1" smd circle
			(at -0.40005 0 90)
			(size 0 0)
			(layers "F.Cu" "F.Mask" "F.Paste")
			(net "PVCCIN_CPU1")
		)
		(pad "2" smd circle
			(at 0.40005 0 90)
			(size 0 0)
			(layers "F.Cu" "F.Mask" "F.Paste")
			(net "GND")
		)
	)
)
